#ISCELL
  mstr_misc dns *
  *
#ISCELL
  pure_quanta quanta_title_block_c *
  *
#ISCELL
  logical_power universal_gnd *
  page301_i1
#ISCELL
  standard offpage *
  page301_i10
#CELL
  pure_quanta q_cap *
  page301_i11
#CELL
  pure_quanta q_res *
  page301_i12
#CELL
  pure_quanta q_res *
  page301_i13
#CELL
  pure_quanta mp5991gluz *
  page301_i14
#CELL
  pure_quanta q_res *
  page301_i15
#ISCELL
  standard offpage *
  page301_i16
#CELL
  pure_quanta q_res *
  page301_i17
#ISCELL
  logical_power universal_power *
  page301_i18
#ISCELL
  logical_power universal_gnd *
  page301_i19
#CELL
  pure_quanta q_cap *
  page301_i2
#CELL
  pure_quanta q_cap *
  page301_i20
#CELL
  pure_quanta q_res *
  page301_i21
#ISCELL
  logical_power universal_gnd *
  page301_i22
#CELL
  pure_quanta q_cap *
  page301_i23
#ISCELL
  standard offpage *
  page301_i24
#ISCELL
  logical_power universal_gnd *
  page301_i25
#ISCELL
  standard offpage *
  page301_i26
#ISCELL
  standard offpage *
  page301_i27
#ISCELL
  logical_power universal_power *
  page301_i28
#CELL
  pure_quanta q_cap *
  page301_i29
#ISCELL
  logical_power universal_gnd *
  page301_i3
#CELL
  pure_quanta q_res *
  page301_i30
#ISCELL
  standard offpage *
  page301_i31
#CELL
  pure_quanta q_res *
  page301_i32
#CELL
  pure_quanta q_res *
  page301_i33
#CELL
  pure_quanta q_res *
  page301_i34
#CELL
  pure_quanta mp5991gluz *
  page301_i35
#ISCELL
  logical_power universal_power *
  page301_i36
#CELL
  pure_quanta q_cap *
  page301_i37
#ISCELL
  logical_power universal_gnd *
  page301_i38
#CELL
  pure_quanta q_res *
  page301_i39
#CELL
  pure_quanta q_cap *
  page301_i4
#CELL
  pure_quanta q_res *
  page301_i40
#ISCELL
  logical_power universal_power *
  page301_i41
#ISCELL
  standard offpage *
  page301_i42
#ISCELL
  standard offpage *
  page301_i43
#ISCELL
  standard offpage *
  page301_i44
#ISCELL
  standard offpage *
  page301_i45
#ISCELL
  standard offpage *
  page301_i46
#CELL
  pure_quanta q_cap *
  page301_i47
#ISCELL
  logical_power universal_gnd *
  page301_i48
#CELL
  pure_quanta q_res *
  page301_i49
#CELL
  pure_quanta q_res *
  page301_i5
#CELL
  pure_quanta q_res *
  page301_i50
#ISCELL
  logical_power universal_power *
  page301_i51
#ISCELL
  standard offpage *
  page301_i52
#ISCELL
  standard offpage *
  page301_i53
#ISCELL
  standard offpage *
  page301_i54
#ISCELL
  standard offpage *
  page301_i55
#ISCELL
  standard offpage *
  page301_i56
#ISCELL
  logical_power universal_power *
  page301_i6
#ISCELL
  standard offpage *
  page301_i7
#ISCELL
  logical_power universal_gnd *
  page301_i8
#ISCELL
  standard offpage *
  page301_i9
